(kicad_pcb
	(version 20221018)
	(generator pcbnew)
	(general
    (thickness 1.62)
  )
	(paper "A4")
	(title_block
    (title "ECP5 - Datacenter Secure Control Module (DC-SCM)")
    (date "2024-07-01")
    (rev "1.2.1")
		(comment 9 "footprints 410-419 of 506")
	)
	(layers
    (0 "F.Cu" signal)
    (1 "In1.Cu" power)
    (2 "In2.Cu" signal)
    (3 "In3.Cu" power)
    (4 "In4.Cu" power)
    (5 "In5.Cu" signal)
    (6 "In6.Cu" power)
    (31 "B.Cu" signal)
    (32 "B.Adhes" user "B.Adhesive")
    (33 "F.Adhes" user "F.Adhesive")
    (34 "B.Paste" user)
    (35 "F.Paste" user)
    (36 "B.SilkS" user "B.Silkscreen")
    (37 "F.SilkS" user "F.Silkscreen")
    (38 "B.Mask" user)
    (39 "F.Mask" user)
    (40 "Dwgs.User" user "User.Drawings")
    (41 "Cmts.User" user "User.Comments")
    (42 "Eco1.User" user "User.Eco1")
    (43 "Eco2.User" user "User.Eco2")
    (44 "Edge.Cuts" user)
    (45 "Margin" user)
    (46 "B.CrtYd" user "B.Courtyard")
    (47 "F.CrtYd" user "F.Courtyard")
    (48 "B.Fab" user)
    (49 "F.Fab" user)
  )
	(footprint "antmicro-footprints:R_0402_1005Metric" (layer "B.Cu")
    (at 67.725 147.8 90)
    (descr "Resistor SMD 0402")
    (tags "resistor SMD 0402")
    (property "Author" "Antmicro")
    (property "License" "Apache-2.0")
    (property "MPN" "CR0402-FX-4701GLF")
    (property "Manufacturer" "Bourns")
    (property "Public" "False")
    (property "Sheetfile" "rot.kicad_sch")
    (property "Sheetname" "RoT")
    (property "Tolerance" "1%")
    (property "Val" "4k7")
    (property "ki_description" "SMD Chip Resistor, 4.7 kohm, ± 1%, 62.5 mW, 0402 [1005 Metric], Thick Film, General Purpose")
    (property "ki_keywords" "0402, SMT, RESISTOR, PASSIVE")
    (attr smd)
    (fp_text reference "R24" (at -2.65 0.048 90) (layer "B.SilkS")
        (effects (font (size 0.7 0.7) (thickness 0.127)) (justify mirror))
    )
    (fp_text value "R_4k7_0402" (at 0 -1.17 90) (layer "B.Fab")
        (effects (font (size 1 1) (thickness 0.15)) (justify mirror))
    )
    (fp_text user "License: Apache-2.0" (at -0.95 -5.169 270) (layer "B.Fab") hide
        (effects (font (size 0.7 0.7) (thickness 0.15)) (justify left bottom mirror))
    )
    (fp_text user "${REFERENCE}" (at 0 0 90) (layer "B.Fab")
        (effects (font (size 0.25 0.25) (thickness 0.04)) (justify mirror))
    )
    (fp_text user "Author: Antmicro" (at -0.95 -4.169 270) (layer "B.Fab") hide
        (effects (font (size 0.7 0.7) (thickness 0.15)) (justify left bottom mirror))
    )
    (fp_rect (start -0.925 0.47) (end 0.925 -0.47)
      (stroke (width 0.05) (type default)) (fill none) (layer "B.CrtYd"))
    (fp_rect (start -0.5 0.25) (end 0.5 -0.25)
      (stroke (width 0.15) (type solid)) (fill none) (layer "B.Fab"))
    (pad "1" smd roundrect (at -0.48 0 90) (size 0.59 0.64) (layers "B.Cu" "B.Paste" "B.Mask") (roundrect_rratio 0.25)
      (net 2 "VCC3V3") (pintype "passive"))
    (pad "2" smd roundrect (at 0.48 0 90) (size 0.59 0.64) (layers "B.Cu" "B.Paste" "B.Mask") (roundrect_rratio 0.25)
      (net 140 "QSPIA1_CS_N") (pintype "passive"))
  )
	(footprint "antmicro-footprints:R_0402_1005Metric" (layer "B.Cu")
    (at 69.725 147.8 90)
    (descr "Resistor SMD 0402")
    (tags "resistor SMD 0402")
    (property "Author" "Antmicro")
    (property "License" "Apache-2.0")
    (property "MPN" "CR0402-FX-1001GLF")
    (property "Manufacturer" "Bourns")
    (property "Public" "False")
    (property "Sheetfile" "rot.kicad_sch")
    (property "Sheetname" "RoT")
    (property "Tolerance" "1%")
    (property "Val" "1k")
    (property "ki_description" "SMD Chip Resistor, 1 kohm, ± 1%, 63 mW, 0402 [1005 Metric], Thick Film, General Purpose")
    (property "ki_keywords" "0402, SMT, RESISTOR, PASSIVE")
    (attr smd)
    (fp_text reference "R28" (at -2.65 0.066 90) (layer "B.SilkS")
        (effects (font (size 0.7 0.7) (thickness 0.127)) (justify mirror))
    )
    (fp_text value "R_1k_0402" (at 0 -1.17 90) (layer "B.Fab")
        (effects (font (size 1 1) (thickness 0.15)) (justify mirror))
    )
    (fp_text user "${REFERENCE}" (at 0 0 90) (layer "B.Fab")
        (effects (font (size 0.25 0.25) (thickness 0.04)) (justify mirror))
    )
    (fp_text user "License: Apache-2.0" (at -0.95 -5.169 270) (layer "B.Fab") hide
        (effects (font (size 0.7 0.7) (thickness 0.15)) (justify left bottom mirror))
    )
    (fp_text user "Author: Antmicro" (at -0.95 -4.169 270) (layer "B.Fab") hide
        (effects (font (size 0.7 0.7) (thickness 0.15)) (justify left bottom mirror))
    )
    (fp_rect (start -0.925 0.47) (end 0.925 -0.47)
      (stroke (width 0.05) (type default)) (fill none) (layer "B.CrtYd"))
    (fp_rect (start -0.5 0.25) (end 0.5 -0.25)
      (stroke (width 0.15) (type solid)) (fill none) (layer "B.Fab"))
    (pad "1" smd roundrect (at -0.48 0 90) (size 0.59 0.64) (layers "B.Cu" "B.Paste" "B.Mask") (roundrect_rratio 0.25)
      (net 2 "VCC3V3") (pintype "passive"))
    (pad "2" smd roundrect (at 0.48 0 90) (size 0.59 0.64) (layers "B.Cu" "B.Paste" "B.Mask") (roundrect_rratio 0.25)
      (net 135 "QSPIA_CLK") (pintype "passive"))
  )
	(footprint "antmicro-footprints:R_0402_1005Metric" (layer "B.Cu")
    (at 70.725 147.8 -90)
    (descr "Resistor SMD 0402")
    (tags "resistor SMD 0402")
    (property "Author" "Antmicro")
    (property "License" "Apache-2.0")
    (property "MPN" "CR0402-FX-1002GLF")
    (property "Manufacturer" "Bourns")
    (property "Public" "False")
    (property "Sheetfile" "rot.kicad_sch")
    (property "Sheetname" "RoT")
    (property "Tolerance" "1%")
    (property "Val" "10k")
    (property "ki_description" "SMD Chip Resistor, 10 kohm, ± 1%, 62.5 mW, 0402 [1005 Metric], Thick Film, General Purpose")
    (property "ki_keywords" "0402, SMT, RESISTOR, PASSIVE")
    (attr smd)
    (fp_text reference "R32" (at 2.65 -0.075 90) (layer "B.SilkS")
        (effects (font (size 0.7 0.7) (thickness 0.127)) (justify mirror))
    )
    (fp_text value "R_10k_0402" (at 0 -1.17 90) (layer "B.Fab")
        (effects (font (size 1 1) (thickness 0.15)) (justify mirror))
    )
    (fp_text user "License: Apache-2.0" (at -0.95 -5.169 90) (layer "B.Fab") hide
        (effects (font (size 0.7 0.7) (thickness 0.15)) (justify left bottom mirror))
    )
    (fp_text user "Author: Antmicro" (at -0.95 -4.169 90) (layer "B.Fab") hide
        (effects (font (size 0.7 0.7) (thickness 0.15)) (justify left bottom mirror))
    )
    (fp_text user "${REFERENCE}" (at 0 0 90) (layer "B.Fab")
        (effects (font (size 0.25 0.25) (thickness 0.04)) (justify mirror))
    )
    (fp_rect (start -0.925 0.47) (end 0.925 -0.47)
      (stroke (width 0.05) (type default)) (fill none) (layer "B.CrtYd"))
    (fp_rect (start -0.5 0.25) (end 0.5 -0.25)
      (stroke (width 0.15) (type solid)) (fill none) (layer "B.Fab"))
    (pad "1" smd roundrect (at -0.48 0 270) (size 0.59 0.64) (layers "B.Cu" "B.Paste" "B.Mask") (roundrect_rratio 0.25)
      (net 136 "QSPIA1_D0") (pintype "passive"))
    (pad "2" smd roundrect (at 0.48 0 270) (size 0.59 0.64) (layers "B.Cu" "B.Paste" "B.Mask") (roundrect_rratio 0.25)
      (net 2 "VCC3V3") (pintype "passive"))
  )
	(footprint "antmicro-footprints:R_0402_1005Metric" (layer "B.Cu")
    (at 65.725 147.8 -90)
    (descr "Resistor SMD 0402")
    (tags "resistor SMD 0402")
    (property "Author" "Antmicro")
    (property "License" "Apache-2.0")
    (property "MPN" "CR0402-FX-1002GLF")
    (property "Manufacturer" "Bourns")
    (property "Public" "False")
    (property "Sheetfile" "rot.kicad_sch")
    (property "Sheetname" "RoT")
    (property "Tolerance" "1%")
    (property "Val" "10k")
    (property "ki_description" "SMD Chip Resistor, 10 kohm, ± 1%, 62.5 mW, 0402 [1005 Metric], Thick Film, General Purpose")
    (property "ki_keywords" "0402, SMT, RESISTOR, PASSIVE")
    (attr smd)
    (fp_text reference "R36" (at 2.65 -0.03 90) (layer "B.SilkS")
        (effects (font (size 0.7 0.7) (thickness 0.127)) (justify mirror))
    )
    (fp_text value "R_10k_0402" (at 0 -1.17 90) (layer "B.Fab")
        (effects (font (size 1 1) (thickness 0.15)) (justify mirror))
    )
    (fp_text user "License: Apache-2.0" (at -0.95 -5.169 90) (layer "B.Fab") hide
        (effects (font (size 0.7 0.7) (thickness 0.15)) (justify left bottom mirror))
    )
    (fp_text user "${REFERENCE}" (at 0 0 90) (layer "B.Fab")
        (effects (font (size 0.25 0.25) (thickness 0.04)) (justify mirror))
    )
    (fp_text user "Author: Antmicro" (at -0.95 -4.169 90) (layer "B.Fab") hide
        (effects (font (size 0.7 0.7) (thickness 0.15)) (justify left bottom mirror))
    )
    (fp_rect (start -0.925 0.47) (end 0.925 -0.47)
      (stroke (width 0.05) (type default)) (fill none) (layer "B.CrtYd"))
    (fp_rect (start -0.5 0.25) (end 0.5 -0.25)
      (stroke (width 0.15) (type solid)) (fill none) (layer "B.Fab"))
    (pad "1" smd roundrect (at -0.48 0 270) (size 0.59 0.64) (layers "B.Cu" "B.Paste" "B.Mask") (roundrect_rratio 0.25)
      (net 138 "QSPIA1_D2") (pintype "passive"))
    (pad "2" smd roundrect (at 0.48 0 270) (size 0.59 0.64) (layers "B.Cu" "B.Paste" "B.Mask") (roundrect_rratio 0.25)
      (net 2 "VCC3V3") (pintype "passive"))
  )
	(footprint "antmicro-footprints:R_0402_1005Metric" (layer "B.Cu")
    (at 68.725 147.8 -90)
    (descr "Resistor SMD 0402")
    (tags "resistor SMD 0402")
    (property "Author" "Antmicro")
    (property "License" "Apache-2.0")
    (property "MPN" "CR0402-FX-1002GLF")
    (property "Manufacturer" "Bourns")
    (property "Public" "False")
    (property "Sheetfile" "rot.kicad_sch")
    (property "Sheetname" "RoT")
    (property "Tolerance" "1%")
    (property "Val" "10k")
    (property "ki_description" "SMD Chip Resistor, 10 kohm, ± 1%, 62.5 mW, 0402 [1005 Metric], Thick Film, General Purpose")
    (property "ki_keywords" "0402, SMT, RESISTOR, PASSIVE")
    (attr smd)
    (fp_text reference "R40" (at 2.65 -0.057 90) (layer "B.SilkS")
        (effects (font (size 0.7 0.7) (thickness 0.127)) (justify mirror))
    )
    (fp_text value "R_10k_0402" (at 0 -1.17 90) (layer "B.Fab")
        (effects (font (size 1 1) (thickness 0.15)) (justify mirror))
    )
    (fp_text user "${REFERENCE}" (at 0 0 90) (layer "B.Fab")
        (effects (font (size 0.25 0.25) (thickness 0.04)) (justify mirror))
    )
    (fp_text user "Author: Antmicro" (at -0.95 -4.169 90) (layer "B.Fab") hide
        (effects (font (size 0.7 0.7) (thickness 0.15)) (justify left bottom mirror))
    )
    (fp_text user "License: Apache-2.0" (at -0.95 -5.169 90) (layer "B.Fab") hide
        (effects (font (size 0.7 0.7) (thickness 0.15)) (justify left bottom mirror))
    )
    (fp_rect (start -0.925 0.47) (end 0.925 -0.47)
      (stroke (width 0.05) (type default)) (fill none) (layer "B.CrtYd"))
    (fp_rect (start -0.5 0.25) (end 0.5 -0.25)
      (stroke (width 0.15) (type solid)) (fill none) (layer "B.Fab"))
    (pad "1" smd roundrect (at -0.48 0 270) (size 0.59 0.64) (layers "B.Cu" "B.Paste" "B.Mask") (roundrect_rratio 0.25)
      (net 139 "QSPIA1_D3") (pintype "passive"))
    (pad "2" smd roundrect (at 0.48 0 270) (size 0.59 0.64) (layers "B.Cu" "B.Paste" "B.Mask") (roundrect_rratio 0.25)
      (net 2 "VCC3V3") (pintype "passive"))
  )
	(footprint "antmicro-footprints:R_0402_1005Metric" (layer "B.Cu")
    (at 66.725 147.8 -90)
    (descr "Resistor SMD 0402")
    (tags "resistor SMD 0402")
    (property "Author" "Antmicro")
    (property "License" "Apache-2.0")
    (property "MPN" "CR0402-FX-1002GLF")
    (property "Manufacturer" "Bourns")
    (property "Public" "False")
    (property "Sheetfile" "rot.kicad_sch")
    (property "Sheetname" "RoT")
    (property "Tolerance" "1%")
    (property "Val" "10k")
    (property "ki_description" "SMD Chip Resistor, 10 kohm, ± 1%, 62.5 mW, 0402 [1005 Metric], Thick Film, General Purpose")
    (property "ki_keywords" "0402, SMT, RESISTOR, PASSIVE")
    (attr smd)
    (fp_text reference "R44" (at 2.65 -0.039 90) (layer "B.SilkS")
        (effects (font (size 0.7 0.7) (thickness 0.127)) (justify mirror))
    )
    (fp_text value "R_10k_0402" (at 0 -1.17 90) (layer "B.Fab")
        (effects (font (size 1 1) (thickness 0.15)) (justify mirror))
    )
    (fp_text user "${REFERENCE}" (at 0 0 90) (layer "B.Fab")
        (effects (font (size 0.25 0.25) (thickness 0.04)) (justify mirror))
    )
    (fp_text user "License: Apache-2.0" (at -0.95 -5.169 90) (layer "B.Fab") hide
        (effects (font (size 0.7 0.7) (thickness 0.15)) (justify left bottom mirror))
    )
    (fp_text user "Author: Antmicro" (at -0.95 -4.169 90) (layer "B.Fab") hide
        (effects (font (size 0.7 0.7) (thickness 0.15)) (justify left bottom mirror))
    )
    (fp_rect (start -0.925 0.47) (end 0.925 -0.47)
      (stroke (width 0.05) (type default)) (fill none) (layer "B.CrtYd"))
    (fp_rect (start -0.5 0.25) (end 0.5 -0.25)
      (stroke (width 0.15) (type solid)) (fill none) (layer "B.Fab"))
    (pad "1" smd roundrect (at -0.48 0 270) (size 0.59 0.64) (layers "B.Cu" "B.Paste" "B.Mask") (roundrect_rratio 0.25)
      (net 137 "QSPIA1_D1") (pintype "passive"))
    (pad "2" smd roundrect (at 0.48 0 270) (size 0.59 0.64) (layers "B.Cu" "B.Paste" "B.Mask") (roundrect_rratio 0.25)
      (net 2 "VCC3V3") (pintype "passive"))
  )
	(footprint "antmicro-footprints:R_0402_1005Metric" (layer "B.Cu")
    (at 78.975 138.8 90)
    (descr "Resistor SMD 0402")
    (tags "resistor SMD 0402")
    (property "Author" "Antmicro")
    (property "License" "Apache-2.0")
    (property "MPN" "CR0402-FX-4701GLF")
    (property "Manufacturer" "Bourns")
    (property "Public" "False")
    (property "Sheetfile" "rot.kicad_sch")
    (property "Sheetname" "RoT")
    (property "Tolerance" "1%")
    (property "Val" "4k7")
    (property "ki_description" "SMD Chip Resistor, 4.7 kohm, ± 1%, 62.5 mW, 0402 [1005 Metric], Thick Film, General Purpose")
    (property "ki_keywords" "0402, SMT, RESISTOR, PASSIVE")
    (attr smd)
    (fp_text reference "R22" (at -3.05 0.278332 90) (layer "B.SilkS")
        (effects (font (size 0.7 0.7) (thickness 0.127)) (justify mirror))
    )
    (fp_text value "R_4k7_0402" (at 0 -1.17 90) (layer "B.Fab")
        (effects (font (size 1 1) (thickness 0.15)) (justify mirror))
    )
    (fp_text user "License: Apache-2.0" (at -0.95 -5.169 270) (layer "B.Fab") hide
        (effects (font (size 0.7 0.7) (thickness 0.15)) (justify left bottom mirror))
    )
    (fp_text user "Author: Antmicro" (at -0.95 -4.169 270) (layer "B.Fab") hide
        (effects (font (size 0.7 0.7) (thickness 0.15)) (justify left bottom mirror))
    )
    (fp_text user "${REFERENCE}" (at 0 0 90) (layer "B.Fab")
        (effects (font (size 0.25 0.25) (thickness 0.04)) (justify mirror))
    )
    (fp_rect (start -0.925 0.47) (end 0.925 -0.47)
      (stroke (width 0.05) (type default)) (fill none) (layer "B.CrtYd"))
    (fp_rect (start -0.5 0.25) (end 0.5 -0.25)
      (stroke (width 0.15) (type solid)) (fill none) (layer "B.Fab"))
    (pad "1" smd roundrect (at -0.48 0 90) (size 0.59 0.64) (layers "B.Cu" "B.Paste" "B.Mask") (roundrect_rratio 0.25)
      (net 2 "VCC3V3") (pintype "passive"))
    (pad "2" smd roundrect (at 0.48 0 90) (size 0.59 0.64) (layers "B.Cu" "B.Paste" "B.Mask") (roundrect_rratio 0.25)
      (net 129 "QSPIB1_CS_N") (pintype "passive"))
  )
	(footprint "antmicro-footprints:R_0402_1005Metric" (layer "B.Cu")
    (at 80.975 138.8 90)
    (descr "Resistor SMD 0402")
    (tags "resistor SMD 0402")
    (property "Author" "Antmicro")
    (property "License" "Apache-2.0")
    (property "MPN" "CR0402-FX-1001GLF")
    (property "Manufacturer" "Bourns")
    (property "Public" "False")
    (property "Sheetfile" "rot.kicad_sch")
    (property "Sheetname" "RoT")
    (property "Tolerance" "1%")
    (property "Val" "1k")
    (property "ki_description" "SMD Chip Resistor, 1 kohm, ± 1%, 63 mW, 0402 [1005 Metric], Thick Film, General Purpose")
    (property "ki_keywords" "0402, SMT, RESISTOR, PASSIVE")
    (attr smd)
    (fp_text reference "R26" (at -3.05 0.326664 90) (layer "B.SilkS")
        (effects (font (size 0.7 0.7) (thickness 0.127)) (justify mirror))
    )
    (fp_text value "R_1k_0402" (at 0 -1.17 90) (layer "B.Fab")
        (effects (font (size 1 1) (thickness 0.15)) (justify mirror))
    )
    (fp_text user "Author: Antmicro" (at -0.95 -4.169 270) (layer "B.Fab") hide
        (effects (font (size 0.7 0.7) (thickness 0.15)) (justify left bottom mirror))
    )
    (fp_text user "License: Apache-2.0" (at -0.95 -5.169 270) (layer "B.Fab") hide
        (effects (font (size 0.7 0.7) (thickness 0.15)) (justify left bottom mirror))
    )
    (fp_text user "${REFERENCE}" (at 0 0 90) (layer "B.Fab")
        (effects (font (size 0.25 0.25) (thickness 0.04)) (justify mirror))
    )
    (fp_rect (start -0.925 0.47) (end 0.925 -0.47)
      (stroke (width 0.05) (type default)) (fill none) (layer "B.CrtYd"))
    (fp_rect (start -0.5 0.25) (end 0.5 -0.25)
      (stroke (width 0.15) (type solid)) (fill none) (layer "B.Fab"))
    (pad "1" smd roundrect (at -0.48 0 90) (size 0.59 0.64) (layers "B.Cu" "B.Paste" "B.Mask") (roundrect_rratio 0.25)
      (net 2 "VCC3V3") (pintype "passive"))
    (pad "2" smd roundrect (at 0.48 0 90) (size 0.59 0.64) (layers "B.Cu" "B.Paste" "B.Mask") (roundrect_rratio 0.25)
      (net 124 "QSPIB_CLK") (pintype "passive"))
  )
	(footprint "antmicro-footprints:R_0402_1005Metric" (layer "B.Cu")
    (at 81.975 138.8 -90)
    (descr "Resistor SMD 0402")
    (tags "resistor SMD 0402")
    (property "Author" "Antmicro")
    (property "License" "Apache-2.0")
    (property "MPN" "CR0402-FX-1002GLF")
    (property "Manufacturer" "Bourns")
    (property "Public" "False")
    (property "Sheetfile" "rot.kicad_sch")
    (property "Sheetname" "RoT")
    (property "Tolerance" "1%")
    (property "Val" "10k")
    (property "ki_description" "SMD Chip Resistor, 10 kohm, ± 1%, 62.5 mW, 0402 [1005 Metric], Thick Film, General Purpose")
    (property "ki_keywords" "0402, SMT, RESISTOR, PASSIVE")
    (attr smd)
    (fp_text reference "R30" (at 3.05 -0.35083 90) (layer "B.SilkS")
        (effects (font (size 0.7 0.7) (thickness 0.127)) (justify mirror))
    )
    (fp_text value "R_10k_0402" (at 0 -1.17 90) (layer "B.Fab")
        (effects (font (size 1 1) (thickness 0.15)) (justify mirror))
    )
    (fp_text user "${REFERENCE}" (at 0 0 90) (layer "B.Fab")
        (effects (font (size 0.25 0.25) (thickness 0.04)) (justify mirror))
    )
    (fp_text user "License: Apache-2.0" (at -0.95 -5.169 90) (layer "B.Fab") hide
        (effects (font (size 0.7 0.7) (thickness 0.15)) (justify left bottom mirror))
    )
    (fp_text user "Author: Antmicro" (at -0.95 -4.169 90) (layer "B.Fab") hide
        (effects (font (size 0.7 0.7) (thickness 0.15)) (justify left bottom mirror))
    )
    (fp_rect (start -0.925 0.47) (end 0.925 -0.47)
      (stroke (width 0.05) (type default)) (fill none) (layer "B.CrtYd"))
    (fp_rect (start -0.5 0.25) (end 0.5 -0.25)
      (stroke (width 0.15) (type solid)) (fill none) (layer "B.Fab"))
    (pad "1" smd roundrect (at -0.48 0 270) (size 0.59 0.64) (layers "B.Cu" "B.Paste" "B.Mask") (roundrect_rratio 0.25)
      (net 125 "QSPIB1_D0") (pintype "passive"))
    (pad "2" smd roundrect (at 0.48 0 270) (size 0.59 0.64) (layers "B.Cu" "B.Paste" "B.Mask") (roundrect_rratio 0.25)
      (net 2 "VCC3V3") (pintype "passive"))
  )
	(footprint "antmicro-footprints:R_0402_1005Metric" (layer "B.Cu")
    (at 76.975 138.8 -90)
    (descr "Resistor SMD 0402")
    (tags "resistor SMD 0402")
    (property "Author" "Antmicro")
    (property "License" "Apache-2.0")
    (property "MPN" "CR0402-FX-1002GLF")
    (property "Manufacturer" "Bourns")
    (property "Public" "False")
    (property "Sheetfile" "rot.kicad_sch")
    (property "Sheetname" "RoT")
    (property "Tolerance" "1%")
    (property "Val" "10k")
    (property "ki_description" "SMD Chip Resistor, 10 kohm, ± 1%, 62.5 mW, 0402 [1005 Metric], Thick Film, General Purpose")
    (property "ki_keywords" "0402, SMT, RESISTOR, PASSIVE")
    (attr smd)
    (fp_text reference "R34" (at 3.05 -0.23 90) (layer "B.SilkS")
        (effects (font (size 0.7 0.7) (thickness 0.127)) (justify mirror))
    )
    (fp_text value "R_10k_0402" (at 0 -1.17 90) (layer "B.Fab")
        (effects (font (size 1 1) (thickness 0.15)) (justify mirror))
    )
    (fp_text user "Author: Antmicro" (at -0.95 -4.169 90) (layer "B.Fab") hide
        (effects (font (size 0.7 0.7) (thickness 0.15)) (justify left bottom mirror))
    )
    (fp_text user "${REFERENCE}" (at 0 0 90) (layer "B.Fab")
        (effects (font (size 0.25 0.25) (thickness 0.04)) (justify mirror))
    )
    (fp_text user "License: Apache-2.0" (at -0.95 -5.169 90) (layer "B.Fab") hide
        (effects (font (size 0.7 0.7) (thickness 0.15)) (justify left bottom mirror))
    )
    (fp_rect (start -0.925 0.47) (end 0.925 -0.47)
      (stroke (width 0.05) (type default)) (fill none) (layer "B.CrtYd"))
    (fp_rect (start -0.5 0.25) (end 0.5 -0.25)
      (stroke (width 0.15) (type solid)) (fill none) (layer "B.Fab"))
    (pad "1" smd roundrect (at -0.48 0 270) (size 0.59 0.64) (layers "B.Cu" "B.Paste" "B.Mask") (roundrect_rratio 0.25)
      (net 127 "QSPIB1_D2") (pintype "passive"))
    (pad "2" smd roundrect (at 0.48 0 270) (size 0.59 0.64) (layers "B.Cu" "B.Paste" "B.Mask") (roundrect_rratio 0.25)
      (net 2 "VCC3V3") (pintype "passive"))
  )
)
